(kicad_pcb
	(version 20260206)
	(generator "pcbnew")
	(generator_version "10.0")
	(general
		(thickness 1.6)
		(legacy_teardrops no)
	)
	(paper "A4")
	(title_block
		(title "04192023_DAF0TMB3IC0_F0TG_MB_C_brd_V02_OCP.brd")
		(comment 1 "Grand Teton / footprints 5553-5560 of 8354")
	)
	(layers
		(0 "F.Cu" signal "TOP")
		(4 "In1.Cu" signal "GND")
		(6 "In2.Cu" signal "IN1")
		(8 "In3.Cu" signal "GND1")
		(10 "In4.Cu" signal "IN2")
		(12 "In5.Cu" signal "GND2")
		(14 "In6.Cu" signal "IN3")
		(16 "In7.Cu" signal "GND3")
		(18 "In8.Cu" signal "VCC")
		(20 "In9.Cu" signal "VCC1")
		(22 "In10.Cu" signal "GND4")
		(24 "In11.Cu" signal "IN4")
		(26 "In12.Cu" signal "GND5")
		(28 "In13.Cu" signal "IN5")
		(30 "In14.Cu" signal "GND6")
		(32 "In15.Cu" signal "IN6")
		(34 "In16.Cu" signal "GND7")
		(2 "B.Cu" signal "BOTTOM")
		(9 "F.Adhes" user "F.Adhesive")
		(11 "B.Adhes" user "B.Adhesive")
		(13 "F.Paste" user "Package Geometry/Pastemask Top")
		(15 "B.Paste" user "Package Geometry/Pastemask Bottom")
		(5 "F.SilkS" user "Ref Des/Silkscreen Top")
		(7 "B.SilkS" user "Ref Des/Silkscreen Bottom")
		(1 "F.Mask" user "Board Geometry/Soldermask Top")
		(3 "B.Mask" user "Board Geometry/Soldermask Bottom")
		(17 "Dwgs.User" user "User.Drawings")
		(19 "Cmts.User" user "User.Comments")
		(21 "Eco1.User" user "User.Eco1")
		(23 "Eco2.User" user "User.Eco2")
		(25 "Edge.Cuts" user "Board Geometry/Outline")
		(27 "Margin" user)
		(31 "F.CrtYd" user "Package Geometry/Place Bound Top")
		(29 "B.CrtYd" user "Package Geometry/Place Bound Bottom")
		(35 "F.Fab" user "Ref Des/Assembly Top")
		(33 "B.Fab" user "Ref Des/Assembly Bottom")
	)
	(footprint ""
		(layer "B.Cu")
		(at 120.47855 -386.766562 90)
		(property "Reference" "C449"
			(at 0 0 90)
			(layer "B.SilkS")
			(hide yes)
			(effects
				(font
					(size 1.27 1.27)
				)
				(justify mirror)
			)
		)
		(property "Value" ""
			(at 0 0 90)
			(layer "B.Fab")
			(effects
				(font
					(size 1.27 1.27)
				)
				(justify mirror)
			)
		)
		(duplicate_pad_numbers_are_jumpers no)
		(fp_line
			(start 0.299974 -0.150114)
			(end -0.299974 -0.150114)
			(stroke
				(width 0.1)
				(type default)
			)
			(layer "B.Fab")
		)
		(fp_line
			(start -0.299974 -0.150114)
			(end -0.299974 0.150114)
			(stroke
				(width 0.1)
				(type default)
			)
			(layer "B.Fab")
		)
		(fp_line
			(start 0.299974 0.150114)
			(end 0.299974 -0.150114)
			(stroke
				(width 0.1)
				(type default)
			)
			(layer "B.Fab")
		)
		(fp_line
			(start -0.299974 0.150114)
			(end 0.299974 0.150114)
			(stroke
				(width 0.1)
				(type default)
			)
			(layer "B.Fab")
		)
		(pad "1" smd rect
			(at 0.2667 0 270)
			(size 0.3048 0.381)
			(layers "B.Cu" "B.Mask" "B.Paste")
			(net "P0V9_CPU1_RT_2D")
		)
		(pad "2" smd rect
			(at -0.2667 0 270)
			(size 0.3048 0.381)
			(layers "B.Cu" "B.Mask" "B.Paste")
			(net "GND")
		)
	)
	(footprint ""
		(layer "B.Cu")
		(at 245.7704 -331.2668 180)
		(property "Reference" "R1515"
			(at 0 0 0)
			(layer "B.SilkS")
			(hide yes)
			(effects
				(font
					(size 1.27 1.27)
				)
				(justify mirror)
			)
		)
		(property "Value" ""
			(at 0 0 0)
			(layer "B.Fab")
			(effects
				(font
					(size 1.27 1.27)
				)
				(justify mirror)
			)
		)
		(duplicate_pad_numbers_are_jumpers no)
		(fp_line
			(start 0.32512 0.175006)
			(end 0.32512 -0.175006)
			(stroke
				(width 0.1)
				(type default)
			)
			(layer "B.Fab")
		)
		(fp_line
			(start 0.32512 -0.175006)
			(end -0.32512 -0.175006)
			(stroke
				(width 0.1)
				(type default)
			)
			(layer "B.Fab")
		)
		(fp_line
			(start -0.32512 0.175006)
			(end 0.32512 0.175006)
			(stroke
				(width 0.1)
				(type default)
			)
			(layer "B.Fab")
		)
		(fp_line
			(start -0.32512 -0.175006)
			(end -0.32512 0.175006)
			(stroke
				(width 0.1)
				(type default)
			)
			(layer "B.Fab")
		)
		(pad "1" smd rect
			(at 0.2667 0)
			(size 0.3048 0.381)
			(layers "B.Cu" "B.Mask" "B.Paste")
			(net "SMB_MUX_RT_R1_SDA")
		)
		(pad "2" smd rect
			(at -0.2667 0 180)
			(size 0.3048 0.381)
			(layers "B.Cu" "B.Mask" "B.Paste")
			(net "SMB_MUX_RT_R2_SDA")
		)
	)
	(footprint ""
		(layer "B.Cu")
		(at 34.544 -362.966)
		(property "Reference" "PR231"
			(at 0 0 0)
			(layer "B.SilkS")
			(hide yes)
			(effects
				(font
					(size 1.27 1.27)
				)
				(justify mirror)
			)
		)
		(property "Value" ""
			(at 0 0 0)
			(layer "B.Fab")
			(effects
				(font
					(size 1.27 1.27)
				)
				(justify mirror)
			)
		)
		(duplicate_pad_numbers_are_jumpers no)
		(fp_line
			(start -0.7874 -0.4064)
			(end -0.7874 0.4064)
			(stroke
				(width 0.1524)
				(type default)
			)
			(layer "B.SilkS")
		)
		(fp_line
			(start -0.7874 0.4064)
			(end 0.7874 0.4064)
			(stroke
				(width 0.1524)
				(type default)
			)
			(layer "B.SilkS")
		)
		(fp_line
			(start 0.7874 -0.4064)
			(end -0.7874 -0.4064)
			(stroke
				(width 0.1524)
				(type default)
			)
			(layer "B.SilkS")
		)
		(fp_line
			(start 0.7874 0.4064)
			(end 0.7874 -0.4064)
			(stroke
				(width 0.1524)
				(type default)
			)
			(layer "B.SilkS")
		)
		(fp_line
			(start -0.67945 -0.3048)
			(end -0.67945 0.3048)
			(stroke
				(width 0.1)
				(type default)
			)
			(layer "B.Fab")
		)
		(fp_line
			(start -0.67945 0.3048)
			(end -0.120396 0.3048)
			(stroke
				(width 0.1)
				(type default)
			)
			(layer "B.Fab")
		)
		(fp_line
			(start -0.12065 -0.3048)
			(end -0.67945 -0.3048)
			(stroke
				(width 0.1)
				(type default)
			)
			(layer "B.Fab")
		)
		(fp_line
			(start -0.12065 -0.2794)
			(end -0.12065 -0.3048)
			(stroke
				(width 0.1)
				(type default)
			)
			(layer "B.Fab")
		)
		(fp_line
			(start -0.120396 0.2794)
			(end 0.12065 0.2794)
			(stroke
				(width 0.1)
				(type default)
			)
			(layer "B.Fab")
		)
		(fp_line
			(start -0.120396 0.3048)
			(end -0.120396 0.2794)
			(stroke
				(width 0.1)
				(type default)
			)
			(layer "B.Fab")
		)
		(fp_line
			(start 0.12065 -0.305054)
			(end 0.12065 -0.2794)
			(stroke
				(width 0.1)
				(type default)
			)
			(layer "B.Fab")
		)
		(fp_line
			(start 0.12065 -0.2794)
			(end -0.12065 -0.2794)
			(stroke
				(width 0.1)
				(type default)
			)
			(layer "B.Fab")
		)
		(fp_line
			(start 0.12065 0.2794)
			(end 0.12065 0.3048)
			(stroke
				(width 0.1)
				(type default)
			)
			(layer "B.Fab")
		)
		(fp_line
			(start 0.12065 0.3048)
			(end 0.67945 0.3048)
			(stroke
				(width 0.1)
				(type default)
			)
			(layer "B.Fab")
		)
		(fp_line
			(start 0.67945 -0.305054)
			(end 0.12065 -0.305054)
			(stroke
				(width 0.1)
				(type default)
			)
			(layer "B.Fab")
		)
		(fp_line
			(start 0.67945 0.3048)
			(end 0.67945 -0.305054)
			(stroke
				(width 0.1)
				(type default)
			)
			(layer "B.Fab")
		)
		(pad "1" smd circle
			(at 0.40005 0 180)
			(size 0 0)
			(layers "B.Cu" "B.Mask" "B.Paste")
			(net "PVDDCR_CPU1_P1_VMON")
		)
		(pad "2" smd circle
			(at -0.40005 0 180)
			(size 0 0)
			(layers "B.Cu" "B.Mask" "B.Paste")
			(net "GND")
		)
	)
	(footprint ""
		(layer "B.Cu")
		(at 369.425474 -182.676038 -90)
		(property "Reference" "PC486_2"
			(at 0 0 90)
			(layer "B.SilkS")
			(hide yes)
			(effects
				(font
					(size 1.27 1.27)
				)
				(justify mirror)
			)
		)
		(property "Value" ""
			(at 0 0 90)
			(layer "B.Fab")
			(effects
				(font
					(size 1.27 1.27)
				)
				(justify mirror)
			)
		)
		(duplicate_pad_numbers_are_jumpers no)
		(fp_line
			(start -1.524 0.762)
			(end 1.524 0.762)
			(stroke
				(width 0.1524)
				(type default)
			)
			(layer "B.SilkS")
		)
		(fp_line
			(start 1.524 0.762)
			(end 1.524 -0.762)
			(stroke
				(width 0.1524)
				(type default)
			)
			(layer "B.SilkS")
		)
		(fp_line
			(start -1.524 -0.762)
			(end -1.524 0.762)
			(stroke
				(width 0.1524)
				(type default)
			)
			(layer "B.SilkS")
		)
		(fp_line
			(start 1.524 -0.762)
			(end -1.524 -0.762)
			(stroke
				(width 0.1524)
				(type default)
			)
			(layer "B.SilkS")
		)
		(fp_line
			(start -1.1049 0.724916)
			(end -1.1049 -0.724916)
			(stroke
				(width 0.1)
				(type default)
			)
			(layer "B.Fab")
		)
		(fp_line
			(start 1.1049 0.724916)
			(end -1.1049 0.724916)
			(stroke
				(width 0.1)
				(type default)
			)
			(layer "B.Fab")
		)
		(fp_line
			(start -1.1049 -0.724916)
			(end 1.1049 -0.724916)
			(stroke
				(width 0.1)
				(type default)
			)
			(layer "B.Fab")
		)
		(fp_line
			(start 1.1049 -0.724916)
			(end 1.1049 0.724916)
			(stroke
				(width 0.1)
				(type default)
			)
			(layer "B.Fab")
		)
		(pad "1" smd rect
			(at 0.889 0 270)
			(size 1.016 1.27)
			(layers "B.Cu" "B.Mask" "B.Paste")
			(net "SW_P12V_AUX_PVDDCR_CPU0_P0_FLT")
		)
		(pad "2" smd rect
			(at -0.889 0 270)
			(size 1.016 1.27)
			(layers "B.Cu" "B.Mask" "B.Paste")
			(net "GND")
		)
	)
	(footprint ""
		(layer "B.Cu")
		(at 283.645356 -418.976302 180)
		(property "Reference" "C78"
			(at 0 0 0)
			(layer "B.SilkS")
			(hide yes)
			(effects
				(font
					(size 1.27 1.27)
				)
				(justify mirror)
			)
		)
		(property "Value" ""
			(at 0 0 0)
			(layer "B.Fab")
			(effects
				(font
					(size 1.27 1.27)
				)
				(justify mirror)
			)
		)
		(duplicate_pad_numbers_are_jumpers no)
		(fp_line
			(start 0.7874 0.4064)
			(end 0.7874 -0.4064)
			(stroke
				(width 0.1524)
				(type default)
			)
			(layer "B.SilkS")
		)
		(fp_line
			(start 0.7874 -0.4064)
			(end -0.7874 -0.4064)
			(stroke
				(width 0.1524)
				(type default)
			)
			(layer "B.SilkS")
		)
		(fp_line
			(start -0.7874 0.4064)
			(end 0.7874 0.4064)
			(stroke
				(width 0.1524)
				(type default)
			)
			(layer "B.SilkS")
		)
		(fp_line
			(start -0.7874 -0.4064)
			(end -0.7874 0.4064)
			(stroke
				(width 0.1524)
				(type default)
			)
			(layer "B.SilkS")
		)
		(fp_line
			(start 0.67945 0.3048)
			(end 0.67945 -0.305054)
			(stroke
				(width 0.1)
				(type default)
			)
			(layer "B.Fab")
		)
		(fp_line
			(start 0.67945 -0.305054)
			(end 0.12065 -0.305054)
			(stroke
				(width 0.1)
				(type default)
			)
			(layer "B.Fab")
		)
		(fp_line
			(start 0.12065 0.3048)
			(end 0.67945 0.3048)
			(stroke
				(width 0.1)
				(type default)
			)
			(layer "B.Fab")
		)
		(fp_line
			(start 0.12065 0.2794)
			(end 0.12065 0.3048)
			(stroke
				(width 0.1)
				(type default)
			)
			(layer "B.Fab")
		)
		(fp_line
			(start 0.12065 -0.2794)
			(end -0.12065 -0.2794)
			(stroke
				(width 0.1)
				(type default)
			)
			(layer "B.Fab")
		)
		(fp_line
			(start 0.12065 -0.305054)
			(end 0.12065 -0.2794)
			(stroke
				(width 0.1)
				(type default)
			)
			(layer "B.Fab")
		)
		(fp_line
			(start -0.120396 0.3048)
			(end -0.120396 0.2794)
			(stroke
				(width 0.1)
				(type default)
			)
			(layer "B.Fab")
		)
		(fp_line
			(start -0.120396 0.2794)
			(end 0.12065 0.2794)
			(stroke
				(width 0.1)
				(type default)
			)
			(layer "B.Fab")
		)
		(fp_line
			(start -0.12065 -0.2794)
			(end -0.12065 -0.3048)
			(stroke
				(width 0.1)
				(type default)
			)
			(layer "B.Fab")
		)
		(fp_line
			(start -0.12065 -0.3048)
			(end -0.67945 -0.3048)
			(stroke
				(width 0.1)
				(type default)
			)
			(layer "B.Fab")
		)
		(fp_line
			(start -0.67945 0.3048)
			(end -0.120396 0.3048)
			(stroke
				(width 0.1)
				(type default)
			)
			(layer "B.Fab")
		)
		(fp_line
			(start -0.67945 -0.3048)
			(end -0.67945 0.3048)
			(stroke
				(width 0.1)
				(type default)
			)
			(layer "B.Fab")
		)
		(pad "1" smd circle
			(at 0.40005 0)
			(size 0 0)
			(layers "B.Cu" "B.Mask" "B.Paste")
			(net "P3V3_9ZXL045_P0_VDDR")
		)
		(pad "2" smd circle
			(at -0.40005 0)
			(size 0 0)
			(layers "B.Cu" "B.Mask" "B.Paste")
			(net "GND")
		)
	)
	(footprint ""
		(layer "B.Cu")
		(at 216.10193 -324.647306 180)
		(property "Reference" "R1244"
			(at 0 0 0)
			(layer "B.SilkS")
			(hide yes)
			(effects
				(font
					(size 1.27 1.27)
				)
				(justify mirror)
			)
		)
		(property "Value" ""
			(at 0 0 0)
			(layer "B.Fab")
			(effects
				(font
					(size 1.27 1.27)
				)
				(justify mirror)
			)
		)
		(duplicate_pad_numbers_are_jumpers no)
		(fp_line
			(start 0.7874 0.4064)
			(end 0.7874 -0.4064)
			(stroke
				(width 0.1524)
				(type default)
			)
			(layer "B.SilkS")
		)
		(fp_line
			(start 0.7874 -0.4064)
			(end -0.7874 -0.4064)
			(stroke
				(width 0.1524)
				(type default)
			)
			(layer "B.SilkS")
		)
		(fp_line
			(start -0.7874 0.4064)
			(end 0.7874 0.4064)
			(stroke
				(width 0.1524)
				(type default)
			)
			(layer "B.SilkS")
		)
		(fp_line
			(start -0.7874 -0.4064)
			(end -0.7874 0.4064)
			(stroke
				(width 0.1524)
				(type default)
			)
			(layer "B.SilkS")
		)
		(fp_line
			(start 0.67945 0.3048)
			(end 0.67945 -0.305054)
			(stroke
				(width 0.1)
				(type default)
			)
			(layer "B.Fab")
		)
		(fp_line
			(start 0.67945 -0.305054)
			(end 0.12065 -0.305054)
			(stroke
				(width 0.1)
				(type default)
			)
			(layer "B.Fab")
		)
		(fp_line
			(start 0.12065 0.3048)
			(end 0.67945 0.3048)
			(stroke
				(width 0.1)
				(type default)
			)
			(layer "B.Fab")
		)
		(fp_line
			(start 0.12065 0.2794)
			(end 0.12065 0.3048)
			(stroke
				(width 0.1)
				(type default)
			)
			(layer "B.Fab")
		)
		(fp_line
			(start 0.12065 -0.2794)
			(end -0.12065 -0.2794)
			(stroke
				(width 0.1)
				(type default)
			)
			(layer "B.Fab")
		)
		(fp_line
			(start 0.12065 -0.305054)
			(end 0.12065 -0.2794)
			(stroke
				(width 0.1)
				(type default)
			)
			(layer "B.Fab")
		)
		(fp_line
			(start -0.120396 0.3048)
			(end -0.120396 0.2794)
			(stroke
				(width 0.1)
				(type default)
			)
			(layer "B.Fab")
		)
		(fp_line
			(start -0.120396 0.2794)
			(end 0.12065 0.2794)
			(stroke
				(width 0.1)
				(type default)
			)
			(layer "B.Fab")
		)
		(fp_line
			(start -0.12065 -0.2794)
			(end -0.12065 -0.3048)
			(stroke
				(width 0.1)
				(type default)
			)
			(layer "B.Fab")
		)
		(fp_line
			(start -0.12065 -0.3048)
			(end -0.67945 -0.3048)
			(stroke
				(width 0.1)
				(type default)
			)
			(layer "B.Fab")
		)
		(fp_line
			(start -0.67945 0.3048)
			(end -0.120396 0.3048)
			(stroke
				(width 0.1)
				(type default)
			)
			(layer "B.Fab")
		)
		(fp_line
			(start -0.67945 -0.3048)
			(end -0.67945 0.3048)
			(stroke
				(width 0.1)
				(type default)
			)
			(layer "B.Fab")
		)
		(pad "1" smd circle
			(at 0.40005 0)
			(size 0 0)
			(layers "B.Cu" "B.Mask" "B.Paste")
			(net "SMB_ADC_SCL_R")
		)
		(pad "2" smd circle
			(at -0.40005 0)
			(size 0 0)
			(layers "B.Cu" "B.Mask" "B.Paste")
			(net "SMB_SEN_TIC_2_3V3AUX_SCL")
		)
	)
	(footprint ""
		(layer "B.Cu")
		(at 156.61894 -390.560052 90)
		(property "Reference" "C372"
			(at 0 0 90)
			(layer "B.SilkS")
			(hide yes)
			(effects
				(font
					(size 1.27 1.27)
				)
				(justify mirror)
			)
		)
		(property "Value" ""
			(at 0 0 90)
			(layer "B.Fab")
			(effects
				(font
					(size 1.27 1.27)
				)
				(justify mirror)
			)
		)
		(duplicate_pad_numbers_are_jumpers no)
		(fp_line
			(start 0.7874 -0.4064)
			(end -0.7874 -0.4064)
			(stroke
				(width 0.1524)
				(type default)
			)
			(layer "B.SilkS")
		)
		(fp_line
			(start -0.7874 -0.4064)
			(end -0.7874 0.4064)
			(stroke
				(width 0.1524)
				(type default)
			)
			(layer "B.SilkS")
		)
		(fp_line
			(start 0.7874 0.4064)
			(end 0.7874 -0.4064)
			(stroke
				(width 0.1524)
				(type default)
			)
			(layer "B.SilkS")
		)
		(fp_line
			(start -0.7874 0.4064)
			(end 0.7874 0.4064)
			(stroke
				(width 0.1524)
				(type default)
			)
			(layer "B.SilkS")
		)
		(fp_line
			(start 0.67945 -0.305054)
			(end 0.12065 -0.305054)
			(stroke
				(width 0.1)
				(type default)
			)
			(layer "B.Fab")
		)
		(fp_line
			(start 0.12065 -0.305054)
			(end 0.12065 -0.2794)
			(stroke
				(width 0.1)
				(type default)
			)
			(layer "B.Fab")
		)
		(fp_line
			(start -0.12065 -0.3048)
			(end -0.67945 -0.3048)
			(stroke
				(width 0.1)
				(type default)
			)
			(layer "B.Fab")
		)
		(fp_line
			(start -0.67945 -0.3048)
			(end -0.67945 0.3048)
			(stroke
				(width 0.1)
				(type default)
			)
			(layer "B.Fab")
		)
		(fp_line
			(start 0.12065 -0.2794)
			(end -0.12065 -0.2794)
			(stroke
				(width 0.1)
				(type default)
			)
			(layer "B.Fab")
		)
		(fp_line
			(start -0.12065 -0.2794)
			(end -0.12065 -0.3048)
			(stroke
				(width 0.1)
				(type default)
			)
			(layer "B.Fab")
		)
		(fp_line
			(start 0.12065 0.2794)
			(end 0.12065 0.3048)
			(stroke
				(width 0.1)
				(type default)
			)
			(layer "B.Fab")
		)
		(fp_line
			(start -0.120396 0.2794)
			(end 0.12065 0.2794)
			(stroke
				(width 0.1)
				(type default)
			)
			(layer "B.Fab")
		)
		(fp_line
			(start 0.67945 0.3048)
			(end 0.67945 -0.305054)
			(stroke
				(width 0.1)
				(type default)
			)
			(layer "B.Fab")
		)
		(fp_line
			(start 0.12065 0.3048)
			(end 0.67945 0.3048)
			(stroke
				(width 0.1)
				(type default)
			)
			(layer "B.Fab")
		)
		(fp_line
			(start -0.120396 0.3048)
			(end -0.120396 0.2794)
			(stroke
				(width 0.1)
				(type default)
			)
			(layer "B.Fab")
		)
		(fp_line
			(start -0.67945 0.3048)
			(end -0.120396 0.3048)
			(stroke
				(width 0.1)
				(type default)
			)
			(layer "B.Fab")
		)
		(pad "1" smd circle
			(at 0.40005 0 270)
			(size 0 0)
			(layers "B.Cu" "B.Mask" "B.Paste")
			(net "P1V8_CPU1_RT2_1A")
		)
		(pad "2" smd circle
			(at -0.40005 0 270)
			(size 0 0)
			(layers "B.Cu" "B.Mask" "B.Paste")
			(net "GND")
		)
	)
	(footprint ""
		(layer "B.Cu")
		(at 409.146248 -396.393162 -90)
		(property "Reference" "C782"
			(at 0 0 90)
			(layer "B.SilkS")
			(hide yes)
			(effects
				(font
					(size 1.27 1.27)
				)
				(justify mirror)
			)
		)
		(property "Value" ""
			(at 0 0 90)
			(layer "B.Fab")
			(effects
				(font
					(size 1.27 1.27)
				)
				(justify mirror)
			)
		)
		(duplicate_pad_numbers_are_jumpers no)
		(fp_line
			(start -0.299974 0.150114)
			(end 0.299974 0.150114)
			(stroke
				(width 0.1)
				(type default)
			)
			(layer "B.Fab")
		)
		(fp_line
			(start 0.299974 0.150114)
			(end 0.299974 -0.150114)
			(stroke
				(width 0.1)
				(type default)
			)
			(layer "B.Fab")
		)
		(fp_line
			(start -0.299974 -0.150114)
			(end -0.299974 0.150114)
			(stroke
				(width 0.1)
				(type default)
			)
			(layer "B.Fab")
		)
		(fp_line
			(start 0.299974 -0.150114)
			(end -0.299974 -0.150114)
			(stroke
				(width 0.1)
				(type default)
			)
			(layer "B.Fab")
		)
		(pad "1" smd rect
			(at 0.2667 0 90)
			(size 0.3048 0.381)
			(layers "B.Cu" "B.Mask" "B.Paste")
			(net "P0V9_CPU0_RT_2D")
		)
		(pad "2" smd rect
			(at -0.2667 0 90)
			(size 0.3048 0.381)
			(layers "B.Cu" "B.Mask" "B.Paste")
			(net "GND")
		)
	)
)
